(kicad_pcb
	(version 20260206)
	(generator "pcbnew")
	(generator_version "10.0")
	(general
		(thickness 1.6)
		(legacy_teardrops no)
	)
	(paper "A4")
	(title_block
		(title "03242023_DA0F0TMBIJ0_F0T_Motherboard_J_brd_V01_OCP.brd")
		(comment 1 "Grand Teton / footprints 2460-2464 of 6105")
	)
	(layers
		(0 "F.Cu" signal "TOP")
		(4 "In1.Cu" signal "GND")
		(6 "In2.Cu" signal "IN1")
		(8 "In3.Cu" signal "GND1")
		(10 "In4.Cu" signal "IN2")
		(12 "In5.Cu" signal "GND2")
		(14 "In6.Cu" signal "IN3")
		(16 "In7.Cu" signal "GND3")
		(18 "In8.Cu" signal "VCC")
		(20 "In9.Cu" signal "VCC1")
		(22 "In10.Cu" signal "GND4")
		(24 "In11.Cu" signal "IN4")
		(26 "In12.Cu" signal "GND5")
		(28 "In13.Cu" signal "IN5")
		(30 "In14.Cu" signal "GND6")
		(32 "In15.Cu" signal "IN6")
		(34 "In16.Cu" signal "GND7")
		(2 "B.Cu" signal "BOTTOM")
		(9 "F.Adhes" user "F.Adhesive")
		(11 "B.Adhes" user "B.Adhesive")
		(13 "F.Paste" user "Package Geometry/Pastemask Top")
		(15 "B.Paste" user "Package Geometry/Pastemask Bottom")
		(5 "F.SilkS" user "Ref Des/Silkscreen Top")
		(7 "B.SilkS" user "Ref Des/Silkscreen Bottom")
		(1 "F.Mask" user "Board Geometry/Soldermask Top")
		(3 "B.Mask" user "Board Geometry/Soldermask Bottom")
		(17 "Dwgs.User" user "User.Drawings")
		(19 "Cmts.User" user "User.Comments")
		(21 "Eco1.User" user "User.Eco1")
		(23 "Eco2.User" user "User.Eco2")
		(25 "Edge.Cuts" user "Board Geometry/Outline")
		(27 "Margin" user)
		(31 "F.CrtYd" user "Package Geometry/Place Bound Top")
		(29 "B.CrtYd" user "Package Geometry/Place Bound Bottom")
		(35 "F.Fab" user "Ref Des/Assembly Top")
		(33 "B.Fab" user "Ref Des/Assembly Bottom")
	)
	(footprint ""
		(layer "F.Cu")
		(at 200.533 -97.8662 180)
		(property "Reference" "C2383"
			(at 0 0 180)
			(layer "F.SilkS")
			(hide yes)
			(effects
				(font
					(size 1.27 1.27)
				)
			)
		)
		(property "Value" ""
			(at 0 0 180)
			(layer "F.Fab")
			(effects
				(font
					(size 1.27 1.27)
				)
			)
		)
		(duplicate_pad_numbers_are_jumpers no)
		(fp_line
			(start 0.7874 0.4064)
			(end -0.7874 0.4064)
			(stroke
				(width 0.1524)
				(type default)
			)
			(layer "F.SilkS")
		)
		(fp_line
			(start 0.7874 -0.4064)
			(end 0.7874 0.4064)
			(stroke
				(width 0.1524)
				(type default)
			)
			(layer "F.SilkS")
		)
		(fp_line
			(start -0.7874 0.4064)
			(end -0.7874 -0.4064)
			(stroke
				(width 0.1524)
				(type default)
			)
			(layer "F.SilkS")
		)
		(fp_line
			(start -0.7874 -0.4064)
			(end 0.7874 -0.4064)
			(stroke
				(width 0.1524)
				(type default)
			)
			(layer "F.SilkS")
		)
		(fp_line
			(start 0.67945 0.3048)
			(end 0.120396 0.3048)
			(stroke
				(width 0.1)
				(type default)
			)
			(layer "F.Fab")
		)
		(fp_line
			(start 0.67945 -0.3048)
			(end 0.67945 0.3048)
			(stroke
				(width 0.1)
				(type default)
			)
			(layer "F.Fab")
		)
		(fp_line
			(start 0.12065 -0.2794)
			(end 0.12065 -0.3048)
			(stroke
				(width 0.1)
				(type default)
			)
			(layer "F.Fab")
		)
		(fp_line
			(start 0.12065 -0.3048)
			(end 0.67945 -0.3048)
			(stroke
				(width 0.1)
				(type default)
			)
			(layer "F.Fab")
		)
		(fp_line
			(start 0.120396 0.3048)
			(end 0.120396 0.2794)
			(stroke
				(width 0.1)
				(type default)
			)
			(layer "F.Fab")
		)
		(fp_line
			(start 0.120396 0.2794)
			(end -0.12065 0.2794)
			(stroke
				(width 0.1)
				(type default)
			)
			(layer "F.Fab")
		)
		(fp_line
			(start -0.12065 0.3048)
			(end -0.67945 0.3048)
			(stroke
				(width 0.1)
				(type default)
			)
			(layer "F.Fab")
		)
		(fp_line
			(start -0.12065 0.2794)
			(end -0.12065 0.3048)
			(stroke
				(width 0.1)
				(type default)
			)
			(layer "F.Fab")
		)
		(fp_line
			(start -0.12065 -0.2794)
			(end 0.12065 -0.2794)
			(stroke
				(width 0.1)
				(type default)
			)
			(layer "F.Fab")
		)
		(fp_line
			(start -0.12065 -0.305054)
			(end -0.12065 -0.2794)
			(stroke
				(width 0.1)
				(type default)
			)
			(layer "F.Fab")
		)
		(fp_line
			(start -0.67945 0.3048)
			(end -0.67945 -0.305054)
			(stroke
				(width 0.1)
				(type default)
			)
			(layer "F.Fab")
		)
		(fp_line
			(start -0.67945 -0.305054)
			(end -0.12065 -0.305054)
			(stroke
				(width 0.1)
				(type default)
			)
			(layer "F.Fab")
		)
		(pad "1" smd circle
			(at -0.40005 0 180)
			(size 0 0)
			(layers "F.Cu" "F.Mask" "F.Paste")
			(net "P12V_AUX")
		)
		(pad "2" smd circle
			(at 0.40005 0 180)
			(size 0 0)
			(layers "F.Cu" "F.Mask" "F.Paste")
			(net "GND")
		)
	)
	(footprint ""
		(layer "F.Cu")
		(at 301.01032 -411.604206 -90)
		(property "Reference" "C2364"
			(at 0 0 270)
			(layer "F.SilkS")
			(hide yes)
			(effects
				(font
					(size 1.27 1.27)
				)
			)
		)
		(property "Value" ""
			(at 0 0 270)
			(layer "F.Fab")
			(effects
				(font
					(size 1.27 1.27)
				)
			)
		)
		(duplicate_pad_numbers_are_jumpers no)
		(fp_line
			(start -0.7874 0.4064)
			(end -0.7874 -0.4064)
			(stroke
				(width 0.1524)
				(type default)
			)
			(layer "F.SilkS")
		)
		(fp_line
			(start 0.7874 0.4064)
			(end -0.7874 0.4064)
			(stroke
				(width 0.1524)
				(type default)
			)
			(layer "F.SilkS")
		)
		(fp_line
			(start -0.7874 -0.4064)
			(end 0.7874 -0.4064)
			(stroke
				(width 0.1524)
				(type default)
			)
			(layer "F.SilkS")
		)
		(fp_line
			(start 0.7874 -0.4064)
			(end 0.7874 0.4064)
			(stroke
				(width 0.1524)
				(type default)
			)
			(layer "F.SilkS")
		)
		(fp_line
			(start -0.67945 0.3048)
			(end -0.67945 -0.305054)
			(stroke
				(width 0.1)
				(type default)
			)
			(layer "F.Fab")
		)
		(fp_line
			(start -0.12065 0.3048)
			(end -0.67945 0.3048)
			(stroke
				(width 0.1)
				(type default)
			)
			(layer "F.Fab")
		)
		(fp_line
			(start 0.120396 0.3048)
			(end 0.120396 0.2794)
			(stroke
				(width 0.1)
				(type default)
			)
			(layer "F.Fab")
		)
		(fp_line
			(start 0.67945 0.3048)
			(end 0.120396 0.3048)
			(stroke
				(width 0.1)
				(type default)
			)
			(layer "F.Fab")
		)
		(fp_line
			(start -0.12065 0.2794)
			(end -0.12065 0.3048)
			(stroke
				(width 0.1)
				(type default)
			)
			(layer "F.Fab")
		)
		(fp_line
			(start 0.120396 0.2794)
			(end -0.12065 0.2794)
			(stroke
				(width 0.1)
				(type default)
			)
			(layer "F.Fab")
		)
		(fp_line
			(start -0.12065 -0.2794)
			(end 0.12065 -0.2794)
			(stroke
				(width 0.1)
				(type default)
			)
			(layer "F.Fab")
		)
		(fp_line
			(start 0.12065 -0.2794)
			(end 0.12065 -0.3048)
			(stroke
				(width 0.1)
				(type default)
			)
			(layer "F.Fab")
		)
		(fp_line
			(start 0.12065 -0.3048)
			(end 0.67945 -0.3048)
			(stroke
				(width 0.1)
				(type default)
			)
			(layer "F.Fab")
		)
		(fp_line
			(start 0.67945 -0.3048)
			(end 0.67945 0.3048)
			(stroke
				(width 0.1)
				(type default)
			)
			(layer "F.Fab")
		)
		(fp_line
			(start -0.67945 -0.305054)
			(end -0.12065 -0.305054)
			(stroke
				(width 0.1)
				(type default)
			)
			(layer "F.Fab")
		)
		(fp_line
			(start -0.12065 -0.305054)
			(end -0.12065 -0.2794)
			(stroke
				(width 0.1)
				(type default)
			)
			(layer "F.Fab")
		)
		(pad "1" smd circle
			(at -0.40005 0 270)
			(size 0 0)
			(layers "F.Cu" "F.Mask" "F.Paste")
			(net "P3V3_AUX")
		)
		(pad "2" smd circle
			(at 0.40005 0 270)
			(size 0 0)
			(layers "F.Cu" "F.Mask" "F.Paste")
			(net "GND")
		)
	)
	(footprint ""
		(layer "F.Cu")
		(at 113.21288 -101.793548 90)
		(property "Reference" "R1443"
			(at 0 0 90)
			(layer "F.SilkS")
			(hide yes)
			(effects
				(font
					(size 1.27 1.27)
				)
			)
		)
		(property "Value" ""
			(at 0 0 90)
			(layer "F.Fab")
			(effects
				(font
					(size 1.27 1.27)
				)
			)
		)
		(duplicate_pad_numbers_are_jumpers no)
		(fp_line
			(start 0.7874 -0.4064)
			(end 0.7874 0.4064)
			(stroke
				(width 0.1524)
				(type default)
			)
			(layer "F.SilkS")
		)
		(fp_line
			(start -0.7874 -0.4064)
			(end 0.7874 -0.4064)
			(stroke
				(width 0.1524)
				(type default)
			)
			(layer "F.SilkS")
		)
		(fp_line
			(start 0.7874 0.4064)
			(end -0.7874 0.4064)
			(stroke
				(width 0.1524)
				(type default)
			)
			(layer "F.SilkS")
		)
		(fp_line
			(start -0.7874 0.4064)
			(end -0.7874 -0.4064)
			(stroke
				(width 0.1524)
				(type default)
			)
			(layer "F.SilkS")
		)
		(fp_line
			(start -0.12065 -0.305054)
			(end -0.12065 -0.2794)
			(stroke
				(width 0.1)
				(type default)
			)
			(layer "F.Fab")
		)
		(fp_line
			(start -0.67945 -0.305054)
			(end -0.12065 -0.305054)
			(stroke
				(width 0.1)
				(type default)
			)
			(layer "F.Fab")
		)
		(fp_line
			(start 0.67945 -0.3048)
			(end 0.67945 0.3048)
			(stroke
				(width 0.1)
				(type default)
			)
			(layer "F.Fab")
		)
		(fp_line
			(start 0.12065 -0.3048)
			(end 0.67945 -0.3048)
			(stroke
				(width 0.1)
				(type default)
			)
			(layer "F.Fab")
		)
		(fp_line
			(start 0.12065 -0.2794)
			(end 0.12065 -0.3048)
			(stroke
				(width 0.1)
				(type default)
			)
			(layer "F.Fab")
		)
		(fp_line
			(start -0.12065 -0.2794)
			(end 0.12065 -0.2794)
			(stroke
				(width 0.1)
				(type default)
			)
			(layer "F.Fab")
		)
		(fp_line
			(start 0.120396 0.2794)
			(end -0.12065 0.2794)
			(stroke
				(width 0.1)
				(type default)
			)
			(layer "F.Fab")
		)
		(fp_line
			(start -0.12065 0.2794)
			(end -0.12065 0.3048)
			(stroke
				(width 0.1)
				(type default)
			)
			(layer "F.Fab")
		)
		(fp_line
			(start 0.67945 0.3048)
			(end 0.120396 0.3048)
			(stroke
				(width 0.1)
				(type default)
			)
			(layer "F.Fab")
		)
		(fp_line
			(start 0.120396 0.3048)
			(end 0.120396 0.2794)
			(stroke
				(width 0.1)
				(type default)
			)
			(layer "F.Fab")
		)
		(fp_line
			(start -0.12065 0.3048)
			(end -0.67945 0.3048)
			(stroke
				(width 0.1)
				(type default)
			)
			(layer "F.Fab")
		)
		(fp_line
			(start -0.67945 0.3048)
			(end -0.67945 -0.305054)
			(stroke
				(width 0.1)
				(type default)
			)
			(layer "F.Fab")
		)
		(pad "1" smd circle
			(at -0.40005 0 90)
			(size 0 0)
			(layers "F.Cu" "F.Mask" "F.Paste")
			(net "PWRGD_CPUPWRGD_LVC1")
		)
		(pad "2" smd circle
			(at 0.40005 0 90)
			(size 0 0)
			(layers "F.Cu" "F.Mask" "F.Paste")
			(net "PWRGD_CPUPWRGD_LVC1_R")
		)
	)
	(footprint ""
		(layer "F.Cu")
		(at 428.179992 -381.218948)
		(property "Reference" "Q69"
			(at 0.610108 -2.01803 0)
			(unlocked yes)
			(layer "F.SilkS")
			(effects
				(font
					(size 0.7874 0.5842)
					(thickness 0.1524)
				)
				(justify left)
			)
		)
		(property "Value" ""
			(at 0 0 0)
			(layer "F.Fab")
			(effects
				(font
					(size 1.27 1.27)
				)
			)
		)
		(duplicate_pad_numbers_are_jumpers no)
		(fp_line
			(start -1.332738 -1.100074)
			(end -0.4826 -1.100074)
			(stroke
				(width 0.1524)
				(type default)
			)
			(layer "F.SilkS")
		)
		(fp_line
			(start -1.332738 1.100074)
			(end -1.332738 -1.100074)
			(stroke
				(width 0.1524)
				(type default)
			)
			(layer "F.SilkS")
		)
		(fp_line
			(start -0.4826 -1.100074)
			(end 0 -0.541274)
			(stroke
				(width 0.1524)
				(type default)
			)
			(layer "F.SilkS")
		)
		(fp_line
			(start 0 -0.541274)
			(end 0.4826 -1.100074)
			(stroke
				(width 0.1524)
				(type default)
			)
			(layer "F.SilkS")
		)
		(fp_line
			(start 0.4826 -1.100074)
			(end 1.332738 -1.100074)
			(stroke
				(width 0.1524)
				(type default)
			)
			(layer "F.SilkS")
		)
		(fp_line
			(start 1.332738 -1.100074)
			(end 1.332738 1.100074)
			(stroke
				(width 0.1524)
				(type default)
			)
			(layer "F.SilkS")
		)
		(fp_line
			(start 1.332738 1.100074)
			(end -1.332738 1.100074)
			(stroke
				(width 0.1524)
				(type default)
			)
			(layer "F.SilkS")
		)
		(fp_poly
			(pts
				(xy -0.552958 -2.070608) (xy -0.903986 -1.368552) (xy -1.255014 -2.070608)
			)
			(stroke
				(width 0)
				(type default)
			)
			(fill yes)
			(layer "F.SilkS")
		)
		(fp_line
			(start -0.674878 -1.100074)
			(end 0.674878 -1.100074)
			(stroke
				(width 0.1)
				(type default)
			)
			(layer "F.Fab")
		)
		(fp_line
			(start -0.674878 1.100074)
			(end -0.674878 -1.100074)
			(stroke
				(width 0.1)
				(type default)
			)
			(layer "F.Fab")
		)
		(fp_line
			(start 0.674878 -1.100074)
			(end 0.674878 1.100074)
			(stroke
				(width 0.1)
				(type default)
			)
			(layer "F.Fab")
		)
		(fp_line
			(start 0.674878 1.100074)
			(end -0.674878 1.100074)
			(stroke
				(width 0.1)
				(type default)
			)
			(layer "F.Fab")
		)
		(fp_poly
			(pts
				(xy -2.2352 -0.298958) (xy -2.2352 -1.001014) (xy -1.533144 -0.649986)
			)
			(stroke
				(width 0)
				(type default)
			)
			(fill yes)
			(layer "F.Fab")
		)
		(pad "1" smd rect
			(at -0.94996 -0.649986 90)
			(size 0.4318 0.508)
			(layers "F.Cu" "F.Mask" "F.Paste")
			(net "GND")
		)
		(pad "2" smd rect
			(at -0.94996 0 90)
			(size 0.4318 0.508)
			(layers "F.Cu" "F.Mask" "F.Paste")
			(net "RST_BMC_FROM_SWB_N")
		)
		(pad "3" smd rect
			(at -0.94996 0.649986 90)
			(size 0.4318 0.508)
			(layers "F.Cu" "F.Mask" "F.Paste")
			(net "RST_BMC_FROM_SWB_ISO_N")
		)
		(pad "4" smd rect
			(at 0.94996 0.649986 90)
			(size 0.4318 0.508)
			(layers "F.Cu" "F.Mask" "F.Paste")
			(net "GND")
		)
		(pad "5" smd rect
			(at 0.94996 0 90)
			(size 0.4318 0.508)
			(layers "F.Cu" "F.Mask" "F.Paste")
			(net "RST_BMC_FROM_SWB")
		)
		(pad "6" smd rect
			(at 0.94996 -0.649986 90)
			(size 0.4318 0.508)
			(layers "F.Cu" "F.Mask" "F.Paste")
			(net "RST_BMC_FROM_SWB")
		)
	)
	(footprint ""
		(layer "F.Cu")
		(at 129.59588 -103.723948 -90)
		(property "Reference" "Q141"
			(at -0.162052 -2.00279 90)
			(unlocked yes)
			(layer "F.SilkS")
			(effects
				(font
					(size 0.7874 0.5842)
					(thickness 0.1524)
				)
			)
		)
		(property "Value" ""
			(at 0 0 270)
			(layer "F.Fab")
			(effects
				(font
					(size 1.27 1.27)
				)
			)
		)
		(duplicate_pad_numbers_are_jumpers no)
		(fp_line
			(start -1.376172 1.199896)
			(end -1.376172 -1.199896)
			(stroke
				(width 0.1524)
				(type default)
			)
			(layer "F.SilkS")
		)
		(fp_line
			(start 1.376172 1.199896)
			(end -1.376172 1.199896)
			(stroke
				(width 0.1524)
				(type default)
			)
			(layer "F.SilkS")
		)
		(fp_line
			(start 0 -0.762)
			(end 0.508 -1.199896)
			(stroke
				(width 0.1524)
				(type default)
			)
			(layer "F.SilkS")
		)
		(fp_line
			(start -1.376172 -1.199896)
			(end -0.508 -1.199896)
			(stroke
				(width 0.1524)
				(type default)
			)
			(layer "F.SilkS")
		)
		(fp_line
			(start -0.508 -1.199896)
			(end 0 -0.762)
			(stroke
				(width 0.1524)
				(type default)
			)
			(layer "F.SilkS")
		)
		(fp_line
			(start 0.508 -1.199896)
			(end 1.376172 -1.199896)
			(stroke
				(width 0.1524)
				(type default)
			)
			(layer "F.SilkS")
		)
		(fp_line
			(start 1.376172 -1.199896)
			(end 1.376172 1.199896)
			(stroke
				(width 0.1524)
				(type default)
			)
			(layer "F.SilkS")
		)
		(fp_poly
			(pts
				(xy -1.4605 -0.7493) (xy -2.2225 -1.1303) (xy -2.2225 -0.3683)
			)
			(stroke
				(width 0)
				(type default)
			)
			(fill yes)
			(layer "F.SilkS")
		)
		(fp_line
			(start -0.674878 1.100074)
			(end -0.674878 -1.100074)
			(stroke
				(width 0.1)
				(type default)
			)
			(layer "F.Fab")
		)
		(fp_line
			(start 0.674878 1.100074)
			(end -0.674878 1.100074)
			(stroke
				(width 0.1)
				(type default)
			)
			(layer "F.Fab")
		)
		(fp_line
			(start -0.674878 -1.100074)
			(end 0.674878 -1.100074)
			(stroke
				(width 0.1)
				(type default)
			)
			(layer "F.Fab")
		)
		(fp_line
			(start 0.674878 -1.100074)
			(end 0.674878 1.100074)
			(stroke
				(width 0.1)
				(type default)
			)
			(layer "F.Fab")
		)
		(fp_poly
			(pts
				(xy -1.4605 -0.7493) (xy -2.2225 -1.1303) (xy -2.2225 -0.3683)
			)
			(stroke
				(width 0)
				(type default)
			)
			(fill yes)
			(layer "F.Fab")
		)
		(pad "1" smd rect
			(at -0.899922 -0.750062 180)
			(size 0.6096 0.6096)
			(layers "F.Cu" "F.Mask" "F.Paste")
			(net "GND")
		)
		(pad "2" smd rect
			(at -0.899922 0 180)
			(size 0.4064 0.6096)
			(layers "F.Cu" "F.Mask" "F.Paste")
			(net "H_CPU0_MEMTRIP_R")
		)
		(pad "3" smd rect
			(at -0.899922 0.750062 180)
			(size 0.6096 0.6096)
			(layers "F.Cu" "F.Mask" "F.Paste")
			(net "H_CPU0_MEMTRIP")
		)
		(pad "4" smd rect
			(at 0.899922 0.750062 180)
			(size 0.6096 0.6096)
			(layers "F.Cu" "F.Mask" "F.Paste")
			(net "PVNN_TERM_CPU0")
		)
		(pad "5" smd rect
			(at 0.899922 0 180)
			(size 0.4064 0.6096)
			(layers "F.Cu" "F.Mask" "F.Paste")
			(net "H_CPU0_MEMTRIP_OUT_VT_R_N")
		)
		(pad "6" smd rect
			(at 0.899922 -0.750062 180)
			(size 0.6096 0.6096)
			(layers "F.Cu" "F.Mask" "F.Paste")
			(net "H_CPU0_MEMTRIP_VT_N")
		)
	)
)
